# BASEBOARD_FAB2 (Tioga Pass) — schematic netlist excerpt (pin names and nets, part order shuffled) for the footprints in the layout excerpt that follows; sources: Cadence DE-HDL packaged netlist, KiCad conversion of Wiwynn_Tioga_Pass_MB.brd

J9U1  SCONN288_H44441003  SCONN  pkg PIP  page 80
  \12v\(1)  = P12V_NVDIMM_GHJ
  VSS(93)  = GND
  DQ(4)  = M_H_DQ<4>
  VSS(92)  = GND
  DQ(0)  = M_H_DQ<0>
  VSS(91)  = GND
  DQS9P  = M_H_DQS_DP<9>
  DQS9N  = M_H_DQS_DN<9>
  VSS(90)  = GND
  DQ(6)  = M_H_DQ<6>
  VSS(89)  = GND
  DQ(2)  = M_H_DQ<2>
  VSS(88)  = GND
  DQ(12)  = M_H_DQ<12>
  VSS(87)  = GND
  DQ(8)  = M_H_DQ<8>
  VSS(86)  = GND
  DQS10P  = M_H_DQS_DP<10>
  DQS10N  = M_H_DQS_DN<10>
  VSS(85)  = GND
  DQ(14)  = M_H_DQ<14>
  VSS(84)  = GND
  DQ(10)  = M_H_DQ<10>
  VSS(83)  = GND
  DQ(20)  = M_H_DQ<20>
  VSS(82)  = GND
  DQ(16)  = M_H_DQ<16>
  VSS(81)  = GND
  DQS11P  = M_H_DQS_DP<11>
  DQS11N  = M_H_DQS_DN<11>
  VSS(80)  = GND
  DQ(22)  = M_H_DQ<22>
  VSS(79)  = GND
  DQ(18)  = M_H_DQ<18>
  VSS(78)  = GND
  DQ(28)  = M_H_DQ<28>
  VSS(77)  = GND
  DQ(24)  = M_H_DQ<24>
  VSS(76)  = GND
  DQS12P  = M_H_DQS_DP<12>
  DQS12N  = M_H_DQS_DN<12>
  VSS(75)  = GND
  DQ(30)  = M_H_DQ<30>
  VSS(74)  = GND
  DQ(26)  = M_H_DQ<26>
  VSS(73)  = GND
  CB(4)  = M_H_ECC<4>
  VSS(72)  = GND
  CB(0)  = M_H_ECC<0>
  VSS(71)  = GND
  DQS17P  = M_H_DQS_DP<17>
  DQS17N  = M_H_DQS_DN<17>
  VSS(70)  = GND
  CB(6)  = M_H_ECC<6>
  VSS(69)  = GND
  CB(2)  = M_H_ECC<2>
  VSS(68)  = GND
  RESET_N  = M_GHJ_RST_N
  VDD(25)  = PVDDQ_GHJ
  CKE(0)  = M_H_CKE<2>
  VDD(24)  = PVDDQ_GHJ
  ACT_N  = M_H_ACT_N
  BG(0)  = M_H_BG<0>
  VDD(23)  = PVDDQ_GHJ
  A12  = M_H_MA<12>
  A9  = M_H_MA<9>
  VDD(22)  = PVDDQ_GHJ
  A8  = M_H_MA<8>
  A6  = M_H_MA<6>
  VDD(21)  = PVDDQ_GHJ
  A3  = M_H_MA<3>
  A1  = M_H_MA<1>
  VDD(20)  = PVDDQ_GHJ
  CK0P  = M_H_CLK_DP<2>
  CK0N  = M_H_CLK_DN<2>
  VDD(19)  = PVDDQ_GHJ
  VTT(1)  = PVTT_GHJ
  EVENT_N  = FM_DIMM_EVENT_COD_N
  A0  = M_H_MA<0>
  VDD(18)  = PVDDQ_GHJ
  BA(0)  = M_H_BA<0>
  A16_RAS_N  = M_H_MA<16>
  VDD(17)  = PVDDQ_GHJ
  S0_N  = M_H_CS_N<4>
  VDD(16)  = PVDDQ_GHJ
  A15_CAS_N  = M_H_MA<15>
  ODT(0)  = M_H_ODT<2>
  VDD(15)  = PVDDQ_GHJ
  S1_N  = M_H_CS_N<5>
  VDD(14)  = PVDDQ_GHJ
  ODT(1)  = M_H_ODT<3>
  VDD(13)  = PVDDQ_GHJ
  S2_N_C(0)  = M_H_CS_N<6>
  VSS(67)  = GND
  DQ(36)  = M_H_DQ<36>
  VSS(66)  = GND
  DQ(32)  = M_H_DQ<32>
  VSS(65)  = GND
  DQS13P  = M_H_DQS_DP<13>
  DQS13N  = M_H_DQS_DN<13>
  VSS(64)  = GND
  DQ(38)  = M_H_DQ<38>
  VSS(63)  = GND
  DQ(34)  = M_H_DQ<34>
  VSS(62)  = GND
  DQ(44)  = M_H_DQ<44>
  VSS(61)  = GND
  DQ(40)  = M_H_DQ<40>
  VSS(60)  = GND
  DQS14P  = M_H_DQS_DP<14>
  DQS14N  = M_H_DQS_DN<14>
  VSS(59)  = GND
  DQ(46)  = M_H_DQ<46>
  VSS(58)  = GND
  DQ(42)  = M_H_DQ<42>
  VSS(57)  = GND
  DQ(52)  = M_H_DQ<52>
  VSS(56)  = GND
  DQ(48)  = M_H_DQ<48>
  VSS(55)  = GND
  DQS15P  = M_H_DQS_DP<15>
  DQS15N  = M_H_DQS_DN<15>
  VSS(54)  = GND
  DQ(54)  = M_H_DQ<54>
  VSS(53)  = GND
  DQ(50)  = M_H_DQ<50>
  VSS(52)  = GND
  DQ(60)  = M_H_DQ<60>
  VSS(51)  = GND
  DQ(56)  = M_H_DQ<56>
  VSS(50)  = GND
  DQS16P  = M_H_DQS_DP<16>
  DQS16N  = M_H_DQS_DN<16>
  VSS(49)  = GND
  DQ(62)  = M_H_DQ<62>
  VSS(48)  = GND
  DQ(58)  = M_H_DQ<58>
  VSS(47)  = GND
  SA(0)  = PVPP_GHJ
  SA(1)  = PVPP_GHJ
  SCL  = SMB_DDR_GHJ_VPP_SCL
  VPP(4)  = PVPP_GHJ
  VPP(3)  = PVPP_GHJ
  RFU(2)  = TP_CH_H_DIMM0_RFU_2
  \12v\(0)  = P12V_NVDIMM_GHJ
  VREFCA  = M_H_VREF
  VSS(46)  = GND
  DQ(5)  = M_H_DQ<5>
  VSS(45)  = GND
  DQ(1)  = M_H_DQ<1>
  VSS(44)  = GND
  DQS0N  = M_H_DQS_DN<0>
  DQS0P  = M_H_DQS_DP<0>
  VSS(43)  = GND
  DQ(7)  = M_H_DQ<7>
  VSS(42)  = GND
  DQ(3)  = M_H_DQ<3>
  VSS(41)  = GND
  DQ(13)  = M_H_DQ<13>
  VSS(40)  = GND
  DQ(9)  = M_H_DQ<9>
  VSS(39)  = GND
  DQS1N  = M_H_DQS_DN<1>
  DQS1P  = M_H_DQS_DP<1>
  VSS(38)  = GND
  DQ(15)  = M_H_DQ<15>
  VSS(37)  = GND
  DQ(11)  = M_H_DQ<11>
  VSS(36)  = GND
  DQ(21)  = M_H_DQ<21>
  VSS(35)  = GND
  DQ(17)  = M_H_DQ<17>
  VSS(34)  = GND
  DQS2N  = M_H_DQS_DN<2>
  DQS2P  = M_H_DQS_DP<2>
  VSS(33)  = GND
  DQ(23)  = M_H_DQ<23>
  VSS(32)  = GND
  DQ(19)  = M_H_DQ<19>
  VSS(31)  = GND
  DQ(29)  = M_H_DQ<29>
  VSS(30)  = GND
  DQ(25)  = M_H_DQ<25>
  VSS(29)  = GND
  DQS3N  = M_H_DQS_DN<3>
  DQS3P  = M_H_DQS_DP<3>
  VSS(28)  = GND
  DQ(31)  = M_H_DQ<31>
  VSS(27)  = GND
  DQ(27)  = M_H_DQ<27>
  VSS(26)  = GND
  CB(5)  = M_H_ECC<5>
  VSS(25)  = GND
  CB(1)  = M_H_ECC<1>
  VSS(24)  = GND
  DQS8N  = M_H_DQS_DN<8>
  DQS8P  = M_H_DQS_DP<8>
  VSS(23)  = GND
  CB(7)  = M_H_ECC<7>
  VSS(22)  = GND
  CB(3)  = M_H_ECC<3>
  VSS(21)  = GND
  CKE(1)  = M_H_CKE<3>
  VDD(12)  = PVDDQ_GHJ
  RFU(0)  = TP_CH_H_DIMM0_RFU_0
  VDD(11)  = PVDDQ_GHJ
  BG(1)  = M_H_BG<1>
  ALERT_N  = M_H_ALERT_N
  VDD(10)  = PVDDQ_GHJ
  A11  = M_H_MA<11>
  A7  = M_H_MA<7>
  VDD(9)  = PVDDQ_GHJ
  A5  = M_H_MA<5>
  A4  = M_H_MA<4>
  VDD(8)  = PVDDQ_GHJ
  A2  = M_H_MA<2>
  VDD(7)  = PVDDQ_GHJ
  CK1P  = M_H_CLK_DP<3>
  CK1N  = M_H_CLK_DN<3>
  VDD(6)  = PVDDQ_GHJ
  VTT(0)  = PVTT_GHJ
  PAR  = M_H_PAR
  VDD(5)  = PVDDQ_GHJ
  BA(1)  = M_H_BA<1>
  A10  = M_H_MA<10>
  VDD(4)  = PVDDQ_GHJ
  RFU(1)  = TP_CH_H_DIMM0_RFU_1
  A14_WE_N  = M_H_MA<14>
  VDD(3)  = PVDDQ_GHJ
  SAVE_N_NC  = FM_ADR_COMPLETE_GHJ_N
  VDD(2)  = PVDDQ_GHJ
  A13  = M_H_MA<13>
  VDD(1)  = PVDDQ_GHJ
  A17  = M_H_MA<17>
  C(2)  = M_H_C<2>
  VDD(0)  = PVDDQ_GHJ
  S3_N_C(1)  = M_H_CS_N<7>
  SA(2)  = GND
  VSS(20)  = GND
  DQ(37)  = M_H_DQ<37>
  VSS(19)  = GND
  DQ(33)  = M_H_DQ<33>
  VSS(18)  = GND
  DQS4N  = M_H_DQS_DN<4>
  DQS4P  = M_H_DQS_DP<4>
  VSS(17)  = GND
  DQ(39)  = M_H_DQ<39>
  VSS(16)  = GND
  DQ(35)  = M_H_DQ<35>
  VSS(15)  = GND
  DQ(45)  = M_H_DQ<45>
  VSS(14)  = GND
  DQ(41)  = M_H_DQ<41>
  VSS(13)  = GND
  DQS5N  = M_H_DQS_DN<5>
  DQS5P  = M_H_DQS_DP<5>
  VSS(12)  = GND
  DQ(47)  = M_H_DQ<47>
  VSS(11)  = GND
  DQ(43)  = M_H_DQ<43>
  VSS(10)  = GND
  DQ(53)  = M_H_DQ<53>
  VSS(9)  = GND
  DQ(49)  = M_H_DQ<49>
  VSS(8)  = GND
  DQS6N  = M_H_DQS_DN<6>
  DQS6P  = M_H_DQS_DP<6>
  VSS(7)  = GND
  DQ(55)  = M_H_DQ<55>
  VSS(6)  = GND
  DQ(51)  = M_H_DQ<51>
  VSS(5)  = GND
  DQ(61)  = M_H_DQ<61>
  VSS(4)  = GND
  DQ(57)  = M_H_DQ<57>
  VSS(3)  = GND
  DQS7N  = M_H_DQS_DN<7>
  DQS7P  = M_H_DQS_DP<7>
  VSS(2)  = GND
  DQ(63)  = M_H_DQ<63>
  VSS(1)  = GND
  DQ(59)  = M_H_DQ<59>
  VSS(0)  = GND
  VDDSPD  = PVPP_GHJ
  SDA  = SMB_DDR_GHJ_VPP_SDA
  VPP(1)  = PVPP_GHJ
  VPP(0)  = PVPP_GHJ
  VPP(2)  = PVPP_GHJ

(kicad_pcb
	(version 20260206)
	(generator "pcbnew")
	(generator_version "10.0")
	(general
		(thickness 1.6)
		(legacy_teardrops no)
	)
	(paper "A4")
	(title_block
		(title "Wiwynn_Tioga_Pass_MB.brd")
		(comment 1 "Tioga Pass / footprint 3114 of 4770 (J9U1), pads 250-291 of 291")
	)
	(layers
		(0 "F.Cu" signal "TOP")
		(4 "In1.Cu" signal "L2GND")
		(6 "In2.Cu" signal "L3")
		(8 "In3.Cu" signal "L4GND")
		(10 "In4.Cu" signal "L5")
		(12 "In5.Cu" signal "L6GND")
		(14 "In6.Cu" signal "L7VCC")
		(16 "In7.Cu" signal "L8VCC")
		(18 "In8.Cu" signal "L9GND")
		(20 "In9.Cu" signal "L10")
		(22 "In10.Cu" signal "L11GND")
		(24 "In11.Cu" signal "L12")
		(26 "In12.Cu" signal "L13GND")
		(2 "B.Cu" signal "BOTTOM")
		(9 "F.Adhes" user "F.Adhesive")
		(11 "B.Adhes" user "B.Adhesive")
		(13 "F.Paste" user "Package Geometry/Pastemask Top")
		(15 "B.Paste" user "Package Geometry/Pastemask Bottom")
		(5 "F.SilkS" user "Ref Des/Silkscreen Top")
		(7 "B.SilkS" user "Ref Des/Silkscreen Bottom")
		(1 "F.Mask" user "Board Geometry/Soldermask Top")
		(3 "B.Mask" user "Board Geometry/Soldermask Bottom")
		(17 "Dwgs.User" user "User.Drawings")
		(19 "Cmts.User" user "User.Comments")
		(21 "Eco1.User" user "User.Eco1")
		(23 "Eco2.User" user "User.Eco2")
		(25 "Edge.Cuts" user "Board Geometry/Outline")
		(27 "Margin" user)
		(31 "F.CrtYd" user "Package Geometry/Place Bound Top")
		(29 "B.CrtYd" user "Package Geometry/Place Bound Bottom")
		(35 "F.Fab" user "Ref Des/Assembly Top")
		(33 "B.Fab" user "Ref Des/Assembly Bottom")
	)
	(footprint ""
		(layer "B.Cu")
		(at 29.699458 -15.222982 90)
		(property "Reference" "J9U1"
			(at 2.276348 37.991542 0)
			(unlocked yes)
			(layer "B.SilkS")
			(effects
				(font
					(size 0.7874 0.5842)
					(thickness 0.1524)
				)
				(justify left mirror)
			)
		)
		(property "Value" ""
			(at 0 0 90)
			(layer "B.Fab")
			(effects
				(font
					(size 1.27 1.27)
				)
				(justify mirror)
			)
		)
		(duplicate_pad_numbers_are_jumpers no)
		(pad "247" smd rect
			(at -4.59994 91.799918 270)
			(size 1.8034 0.508)
			(layers "B.Cu" "B.Mask" "B.Paste")
			(net "M_H_DQ<39>")
		)
		(pad "248" smd rect
			(at -4.59994 92.650056 270)
			(size 1.8034 0.508)
			(layers "B.Cu" "B.Mask" "B.Paste")
			(net "GND")
		)
		(pad "249" smd rect
			(at -4.59994 93.49994 270)
			(size 1.8034 0.508)
			(layers "B.Cu" "B.Mask" "B.Paste")
			(net "M_H_DQ<35>")
		)
		(pad "250" smd rect
			(at -4.59994 94.350078 270)
			(size 1.8034 0.508)
			(layers "B.Cu" "B.Mask" "B.Paste")
			(net "GND")
		)
		(pad "251" smd rect
			(at -4.59994 95.199962 270)
			(size 1.8034 0.508)
			(layers "B.Cu" "B.Mask" "B.Paste")
			(net "M_H_DQ<45>")
		)
		(pad "252" smd rect
			(at -4.59994 96.0501 270)
			(size 1.8034 0.508)
			(layers "B.Cu" "B.Mask" "B.Paste")
			(net "GND")
		)
		(pad "253" smd rect
			(at -4.59994 96.899984 270)
			(size 1.8034 0.508)
			(layers "B.Cu" "B.Mask" "B.Paste")
			(net "M_H_DQ<41>")
		)
		(pad "254" smd rect
			(at -4.59994 97.750122 270)
			(size 1.8034 0.508)
			(layers "B.Cu" "B.Mask" "B.Paste")
			(net "GND")
		)
		(pad "255" smd rect
			(at -4.59994 98.600006 270)
			(size 1.8034 0.508)
			(layers "B.Cu" "B.Mask" "B.Paste")
			(net "M_H_DQS_DN<5>")
		)
		(pad "256" smd rect
			(at -4.59994 99.44989 270)
			(size 1.8034 0.508)
			(layers "B.Cu" "B.Mask" "B.Paste")
			(net "M_H_DQS_DP<5>")
		)
		(pad "257" smd rect
			(at -4.59994 100.300028 270)
			(size 1.8034 0.508)
			(layers "B.Cu" "B.Mask" "B.Paste")
			(net "GND")
		)
		(pad "258" smd rect
			(at -4.59994 101.149912 270)
			(size 1.8034 0.508)
			(layers "B.Cu" "B.Mask" "B.Paste")
			(net "M_H_DQ<47>")
		)
		(pad "259" smd rect
			(at -4.59994 102.00005 270)
			(size 1.8034 0.508)
			(layers "B.Cu" "B.Mask" "B.Paste")
			(net "GND")
		)
		(pad "260" smd rect
			(at -4.59994 102.849934 270)
			(size 1.8034 0.508)
			(layers "B.Cu" "B.Mask" "B.Paste")
			(net "M_H_DQ<43>")
		)
		(pad "261" smd rect
			(at -4.59994 103.700072 270)
			(size 1.8034 0.508)
			(layers "B.Cu" "B.Mask" "B.Paste")
			(net "GND")
		)
		(pad "262" smd rect
			(at -4.59994 104.549956 270)
			(size 1.8034 0.508)
			(layers "B.Cu" "B.Mask" "B.Paste")
			(net "M_H_DQ<53>")
		)
		(pad "263" smd rect
			(at -4.59994 105.400094 270)
			(size 1.8034 0.508)
			(layers "B.Cu" "B.Mask" "B.Paste")
			(net "GND")
		)
		(pad "264" smd rect
			(at -4.59994 106.249978 270)
			(size 1.8034 0.508)
			(layers "B.Cu" "B.Mask" "B.Paste")
			(net "M_H_DQ<49>")
		)
		(pad "265" smd rect
			(at -4.59994 107.100116 270)
			(size 1.8034 0.508)
			(layers "B.Cu" "B.Mask" "B.Paste")
			(net "GND")
		)
		(pad "266" smd rect
			(at -4.59994 107.95 270)
			(size 1.8034 0.508)
			(layers "B.Cu" "B.Mask" "B.Paste")
			(net "M_H_DQS_DN<6>")
		)
		(pad "267" smd rect
			(at -4.59994 108.799884 270)
			(size 1.8034 0.508)
			(layers "B.Cu" "B.Mask" "B.Paste")
			(net "M_H_DQS_DP<6>")
		)
		(pad "268" smd rect
			(at -4.59994 109.650022 270)
			(size 1.8034 0.508)
			(layers "B.Cu" "B.Mask" "B.Paste")
			(net "GND")
		)
		(pad "269" smd rect
			(at -4.59994 110.499906 270)
			(size 1.8034 0.508)
			(layers "B.Cu" "B.Mask" "B.Paste")
			(net "M_H_DQ<55>")
		)
		(pad "270" smd rect
			(at -4.59994 111.350044 270)
			(size 1.8034 0.508)
			(layers "B.Cu" "B.Mask" "B.Paste")
			(net "GND")
		)
		(pad "271" smd rect
			(at -4.59994 112.199928 270)
			(size 1.8034 0.508)
			(layers "B.Cu" "B.Mask" "B.Paste")
			(net "M_H_DQ<51>")
		)
		(pad "272" smd rect
			(at -4.59994 113.050066 270)
			(size 1.8034 0.508)
			(layers "B.Cu" "B.Mask" "B.Paste")
			(net "GND")
		)
		(pad "273" smd rect
			(at -4.59994 113.89995 270)
			(size 1.8034 0.508)
			(layers "B.Cu" "B.Mask" "B.Paste")
			(net "M_H_DQ<61>")
		)
		(pad "274" smd rect
			(at -4.59994 114.750088 270)
			(size 1.8034 0.508)
			(layers "B.Cu" "B.Mask" "B.Paste")
			(net "GND")
		)
		(pad "275" smd rect
			(at -4.59994 115.599972 270)
			(size 1.8034 0.508)
			(layers "B.Cu" "B.Mask" "B.Paste")
			(net "M_H_DQ<57>")
		)
		(pad "276" smd rect
			(at -4.59994 116.45011 270)
			(size 1.8034 0.508)
			(layers "B.Cu" "B.Mask" "B.Paste")
			(net "GND")
		)
		(pad "277" smd rect
			(at -4.59994 117.299994 270)
			(size 1.8034 0.508)
			(layers "B.Cu" "B.Mask" "B.Paste")
			(net "M_H_DQS_DN<7>")
		)
		(pad "278" smd rect
			(at -4.59994 118.149878 270)
			(size 1.8034 0.508)
			(layers "B.Cu" "B.Mask" "B.Paste")
			(net "M_H_DQS_DP<7>")
		)
		(pad "279" smd rect
			(at -4.59994 119.000016 270)
			(size 1.8034 0.508)
			(layers "B.Cu" "B.Mask" "B.Paste")
			(net "GND")
		)
		(pad "280" smd rect
			(at -4.59994 119.8499 270)
			(size 1.8034 0.508)
			(layers "B.Cu" "B.Mask" "B.Paste")
			(net "M_H_DQ<63>")
		)
		(pad "281" smd rect
			(at -4.59994 120.700038 270)
			(size 1.8034 0.508)
			(layers "B.Cu" "B.Mask" "B.Paste")
			(net "GND")
		)
		(pad "282" smd rect
			(at -4.59994 121.549922 270)
			(size 1.8034 0.508)
			(layers "B.Cu" "B.Mask" "B.Paste")
			(net "M_H_DQ<59>")
		)
		(pad "283" smd rect
			(at -4.59994 122.40006 270)
			(size 1.8034 0.508)
			(layers "B.Cu" "B.Mask" "B.Paste")
			(net "GND")
		)
		(pad "284" smd rect
			(at -4.59994 123.249944 270)
			(size 1.8034 0.508)
			(layers "B.Cu" "B.Mask" "B.Paste")
			(net "PVPP_GHJ")
		)
		(pad "285" smd rect
			(at -4.59994 124.100082 270)
			(size 1.8034 0.508)
			(layers "B.Cu" "B.Mask" "B.Paste")
			(net "SMB_DDR_GHJ_VPP_SDA")
		)
		(pad "286" smd rect
			(at -4.59994 124.949966 270)
			(size 1.8034 0.508)
			(layers "B.Cu" "B.Mask" "B.Paste")
			(net "PVPP_GHJ")
		)
		(pad "287" smd rect
			(at -4.59994 125.800104 270)
			(size 1.8034 0.508)
			(layers "B.Cu" "B.Mask" "B.Paste")
			(net "PVPP_GHJ")
		)
		(pad "288" smd rect
			(at -4.59994 126.649988 270)
			(size 1.8034 0.508)
			(layers "B.Cu" "B.Mask" "B.Paste")
			(net "PVPP_GHJ")
		)
	)
)
